# T6G (Grand Teton) — schematic netlist excerpt (pin names and nets, part order shuffled) for the footprints in the layout excerpt that follows; sources: Cadence DE-HDL packaged netlist, KiCad conversion of 04192023_DAF0TMB3IC0_F0TG_MB_C_brd_V02_OCP.brd

R974  Q_RES  4.7K 5% EMPTY  pkg 0201LF  page 276 : A = P1V8_CPU0_RT_1D ; B = RST_RT_CPU0_P0_RESET_R_N
R3430  Q_RES  100K 1% EMPTY  pkg 0402LF  page 126 : A = GPU_FPGA_OVERT_N ; B = GND
R4264  Q_RES  4.7K 5% CHIP  pkg 0402LF  page 241 : A = P3V3_AUX ; B = PWRGD_P3V3_AUX_PDB_BUF_R

(kicad_pcb
	(version 20260206)
	(generator "pcbnew")
	(generator_version "10.0")
	(general
		(thickness 1.6)
		(legacy_teardrops no)
	)
	(paper "A4")
	(title_block
		(title "04192023_DAF0TMB3IC0_F0TG_MB_C_brd_V02_OCP.brd")
		(comment 1 "Grand Teton / footprints 4918-4920 of 8354")
	)
	(layers
		(0 "F.Cu" signal "TOP")
		(4 "In1.Cu" signal "GND")
		(6 "In2.Cu" signal "IN1")
		(8 "In3.Cu" signal "GND1")
		(10 "In4.Cu" signal "IN2")
		(12 "In5.Cu" signal "GND2")
		(14 "In6.Cu" signal "IN3")
		(16 "In7.Cu" signal "GND3")
		(18 "In8.Cu" signal "VCC")
		(20 "In9.Cu" signal "VCC1")
		(22 "In10.Cu" signal "GND4")
		(24 "In11.Cu" signal "IN4")
		(26 "In12.Cu" signal "GND5")
		(28 "In13.Cu" signal "IN5")
		(30 "In14.Cu" signal "GND6")
		(32 "In15.Cu" signal "IN6")
		(34 "In16.Cu" signal "GND7")
		(2 "B.Cu" signal "BOTTOM")
		(9 "F.Adhes" user "F.Adhesive")
		(11 "B.Adhes" user "B.Adhesive")
		(13 "F.Paste" user "Package Geometry/Pastemask Top")
		(15 "B.Paste" user "Package Geometry/Pastemask Bottom")
		(5 "F.SilkS" user "Ref Des/Silkscreen Top")
		(7 "B.SilkS" user "Ref Des/Silkscreen Bottom")
		(1 "F.Mask" user "Board Geometry/Soldermask Top")
		(3 "B.Mask" user "Board Geometry/Soldermask Bottom")
		(17 "Dwgs.User" user "User.Drawings")
		(19 "Cmts.User" user "User.Comments")
		(21 "Eco1.User" user "User.Eco1")
		(23 "Eco2.User" user "User.Eco2")
		(25 "Edge.Cuts" user "Board Geometry/Outline")
		(27 "Margin" user)
		(31 "F.CrtYd" user "Package Geometry/Place Bound Top")
		(29 "B.CrtYd" user "Package Geometry/Place Bound Bottom")
		(35 "F.Fab" user "Ref Des/Assembly Top")
		(33 "B.Fab" user "Ref Des/Assembly Bottom")
	)
	(footprint ""
		(layer "F.Cu")
		(at 296.385742 -397.4084 -90)
		(property "Reference" "R974"
			(at 0 0 270)
			(layer "F.SilkS")
			(hide yes)
			(effects
				(font
					(size 1.27 1.27)
				)
			)
		)
		(property "Value" ""
			(at 0 0 270)
			(layer "F.Fab")
			(effects
				(font
					(size 1.27 1.27)
				)
			)
		)
		(duplicate_pad_numbers_are_jumpers no)
		(fp_line
			(start -0.32512 0.175006)
			(end -0.32512 -0.175006)
			(stroke
				(width 0.1)
				(type default)
			)
			(layer "F.Fab")
		)
		(fp_line
			(start 0.32512 0.175006)
			(end -0.32512 0.175006)
			(stroke
				(width 0.1)
				(type default)
			)
			(layer "F.Fab")
		)
		(fp_line
			(start -0.32512 -0.175006)
			(end 0.32512 -0.175006)
			(stroke
				(width 0.1)
				(type default)
			)
			(layer "F.Fab")
		)
		(fp_line
			(start 0.32512 -0.175006)
			(end 0.32512 0.175006)
			(stroke
				(width 0.1)
				(type default)
			)
			(layer "F.Fab")
		)
		(pad "1" smd rect
			(at -0.2667 0 270)
			(size 0.3048 0.381)
			(layers "F.Cu" "F.Mask" "F.Paste")
			(net "P1V8_CPU0_RT_1D")
		)
		(pad "2" smd rect
			(at 0.2667 0 90)
			(size 0.3048 0.381)
			(layers "F.Cu" "F.Mask" "F.Paste")
			(net "RST_RT_CPU0_P0_RESET_R_N")
		)
	)
	(footprint ""
		(layer "F.Cu")
		(at 279.670256 -430.791366 180)
		(property "Reference" "R4264"
			(at 0 0 180)
			(layer "F.SilkS")
			(hide yes)
			(effects
				(font
					(size 1.27 1.27)
				)
			)
		)
		(property "Value" ""
			(at 0 0 180)
			(layer "F.Fab")
			(effects
				(font
					(size 1.27 1.27)
				)
			)
		)
		(duplicate_pad_numbers_are_jumpers no)
		(fp_line
			(start 0.7874 0.4064)
			(end -0.7874 0.4064)
			(stroke
				(width 0.1524)
				(type default)
			)
			(layer "F.SilkS")
		)
		(fp_line
			(start 0.7874 -0.4064)
			(end 0.7874 0.4064)
			(stroke
				(width 0.1524)
				(type default)
			)
			(layer "F.SilkS")
		)
		(fp_line
			(start -0.7874 0.4064)
			(end -0.7874 -0.4064)
			(stroke
				(width 0.1524)
				(type default)
			)
			(layer "F.SilkS")
		)
		(fp_line
			(start -0.7874 -0.4064)
			(end 0.7874 -0.4064)
			(stroke
				(width 0.1524)
				(type default)
			)
			(layer "F.SilkS")
		)
		(fp_line
			(start 0.67945 0.3048)
			(end 0.120396 0.3048)
			(stroke
				(width 0.1)
				(type default)
			)
			(layer "F.Fab")
		)
		(fp_line
			(start 0.67945 -0.3048)
			(end 0.67945 0.3048)
			(stroke
				(width 0.1)
				(type default)
			)
			(layer "F.Fab")
		)
		(fp_line
			(start 0.12065 -0.2794)
			(end 0.12065 -0.3048)
			(stroke
				(width 0.1)
				(type default)
			)
			(layer "F.Fab")
		)
		(fp_line
			(start 0.12065 -0.3048)
			(end 0.67945 -0.3048)
			(stroke
				(width 0.1)
				(type default)
			)
			(layer "F.Fab")
		)
		(fp_line
			(start 0.120396 0.3048)
			(end 0.120396 0.2794)
			(stroke
				(width 0.1)
				(type default)
			)
			(layer "F.Fab")
		)
		(fp_line
			(start 0.120396 0.2794)
			(end -0.12065 0.2794)
			(stroke
				(width 0.1)
				(type default)
			)
			(layer "F.Fab")
		)
		(fp_line
			(start -0.12065 0.3048)
			(end -0.67945 0.3048)
			(stroke
				(width 0.1)
				(type default)
			)
			(layer "F.Fab")
		)
		(fp_line
			(start -0.12065 0.2794)
			(end -0.12065 0.3048)
			(stroke
				(width 0.1)
				(type default)
			)
			(layer "F.Fab")
		)
		(fp_line
			(start -0.12065 -0.2794)
			(end 0.12065 -0.2794)
			(stroke
				(width 0.1)
				(type default)
			)
			(layer "F.Fab")
		)
		(fp_line
			(start -0.12065 -0.305054)
			(end -0.12065 -0.2794)
			(stroke
				(width 0.1)
				(type default)
			)
			(layer "F.Fab")
		)
		(fp_line
			(start -0.67945 0.3048)
			(end -0.67945 -0.305054)
			(stroke
				(width 0.1)
				(type default)
			)
			(layer "F.Fab")
		)
		(fp_line
			(start -0.67945 -0.305054)
			(end -0.12065 -0.305054)
			(stroke
				(width 0.1)
				(type default)
			)
			(layer "F.Fab")
		)
		(pad "1" smd circle
			(at -0.40005 0 180)
			(size 0 0)
			(layers "F.Cu" "F.Mask" "F.Paste")
			(net "P3V3_AUX")
		)
		(pad "2" smd circle
			(at 0.40005 0 180)
			(size 0 0)
			(layers "F.Cu" "F.Mask" "F.Paste")
			(net "PWRGD_P3V3_AUX_PDB_BUF_R")
		)
	)
	(footprint ""
		(layer "F.Cu")
		(at 308.420516 -433.942744 -90)
		(property "Reference" "R3430"
			(at 0 0 270)
			(layer "F.SilkS")
			(hide yes)
			(effects
				(font
					(size 1.27 1.27)
				)
			)
		)
		(property "Value" ""
			(at 0 0 270)
			(layer "F.Fab")
			(effects
				(font
					(size 1.27 1.27)
				)
			)
		)
		(duplicate_pad_numbers_are_jumpers no)
		(fp_line
			(start -0.7874 0.4064)
			(end -0.7874 -0.4064)
			(stroke
				(width 0.1524)
				(type default)
			)
			(layer "F.SilkS")
		)
		(fp_line
			(start 0.7874 0.4064)
			(end -0.7874 0.4064)
			(stroke
				(width 0.1524)
				(type default)
			)
			(layer "F.SilkS")
		)
		(fp_line
			(start -0.7874 -0.4064)
			(end 0.7874 -0.4064)
			(stroke
				(width 0.1524)
				(type default)
			)
			(layer "F.SilkS")
		)
		(fp_line
			(start 0.7874 -0.4064)
			(end 0.7874 0.4064)
			(stroke
				(width 0.1524)
				(type default)
			)
			(layer "F.SilkS")
		)
		(fp_line
			(start -0.67945 0.3048)
			(end -0.67945 -0.305054)
			(stroke
				(width 0.1)
				(type default)
			)
			(layer "F.Fab")
		)
		(fp_line
			(start -0.12065 0.3048)
			(end -0.67945 0.3048)
			(stroke
				(width 0.1)
				(type default)
			)
			(layer "F.Fab")
		)
		(fp_line
			(start 0.120396 0.3048)
			(end 0.120396 0.2794)
			(stroke
				(width 0.1)
				(type default)
			)
			(layer "F.Fab")
		)
		(fp_line
			(start 0.67945 0.3048)
			(end 0.120396 0.3048)
			(stroke
				(width 0.1)
				(type default)
			)
			(layer "F.Fab")
		)
		(fp_line
			(start -0.12065 0.2794)
			(end -0.12065 0.3048)
			(stroke
				(width 0.1)
				(type default)
			)
			(layer "F.Fab")
		)
		(fp_line
			(start 0.120396 0.2794)
			(end -0.12065 0.2794)
			(stroke
				(width 0.1)
				(type default)
			)
			(layer "F.Fab")
		)
		(fp_line
			(start -0.12065 -0.2794)
			(end 0.12065 -0.2794)
			(stroke
				(width 0.1)
				(type default)
			)
			(layer "F.Fab")
		)
		(fp_line
			(start 0.12065 -0.2794)
			(end 0.12065 -0.3048)
			(stroke
				(width 0.1)
				(type default)
			)
			(layer "F.Fab")
		)
		(fp_line
			(start 0.12065 -0.3048)
			(end 0.67945 -0.3048)
			(stroke
				(width 0.1)
				(type default)
			)
			(layer "F.Fab")
		)
		(fp_line
			(start 0.67945 -0.3048)
			(end 0.67945 0.3048)
			(stroke
				(width 0.1)
				(type default)
			)
			(layer "F.Fab")
		)
		(fp_line
			(start -0.67945 -0.305054)
			(end -0.12065 -0.305054)
			(stroke
				(width 0.1)
				(type default)
			)
			(layer "F.Fab")
		)
		(fp_line
			(start -0.12065 -0.305054)
			(end -0.12065 -0.2794)
			(stroke
				(width 0.1)
				(type default)
			)
			(layer "F.Fab")
		)
		(pad "1" smd circle
			(at -0.40005 0 270)
			(size 0 0)
			(layers "F.Cu" "F.Mask" "F.Paste")
			(net "GPU_FPGA_OVERT_N")
		)
		(pad "2" smd circle
			(at 0.40005 0 270)
			(size 0 0)
			(layers "F.Cu" "F.Mask" "F.Paste")
			(net "GND")
		)
	)
)
